(kicad_pcb
	(version 20260206)
	(generator "pcbnew")
	(generator_version "10.0")
	(general
		(thickness 1.6)
		(legacy_teardrops no)
	)
	(paper "A4")
	(title_block
		(title "01162023_DA0F0TEBIF0_F0T_Expander_BD_F_brd_V02_OCP.brd")
		(comment 1 "Grand Teton / footprints 7402-7409 of 9728")
	)
	(layers
		(0 "F.Cu" signal "TOP")
		(4 "In1.Cu" signal "GND")
		(6 "In2.Cu" signal "VCC")
		(8 "In3.Cu" signal "VCC1")
		(10 "In4.Cu" signal "GND1")
		(12 "In5.Cu" signal "IN1")
		(14 "In6.Cu" signal "GND2")
		(16 "In7.Cu" signal "IN2")
		(18 "In8.Cu" signal "GND3")
		(20 "In9.Cu" signal "IN3")
		(22 "In10.Cu" signal "GND4")
		(24 "In11.Cu" signal "IN4")
		(26 "In12.Cu" signal "GND5")
		(28 "In13.Cu" signal "IN5")
		(30 "In14.Cu" signal "GND6")
		(32 "In15.Cu" signal "IN6")
		(34 "In16.Cu" signal "GND7")
		(2 "B.Cu" signal "BOTTOM")
		(9 "F.Adhes" user "F.Adhesive")
		(11 "B.Adhes" user "B.Adhesive")
		(13 "F.Paste" user "Package Geometry/Pastemask Top")
		(15 "B.Paste" user "Package Geometry/Pastemask Bottom")
		(5 "F.SilkS" user "Ref Des/Silkscreen Top")
		(7 "B.SilkS" user "Ref Des/Silkscreen Bottom")
		(1 "F.Mask" user "Board Geometry/Soldermask Top")
		(3 "B.Mask" user "Board Geometry/Soldermask Bottom")
		(17 "Dwgs.User" user "User.Drawings")
		(19 "Cmts.User" user "User.Comments")
		(21 "Eco1.User" user "User.Eco1")
		(23 "Eco2.User" user "User.Eco2")
		(25 "Edge.Cuts" user "Board Geometry/Outline")
		(27 "Margin" user)
		(31 "F.CrtYd" user "Package Geometry/Place Bound Top")
		(29 "B.CrtYd" user "Package Geometry/Place Bound Bottom")
		(35 "F.Fab" user "Ref Des/Assembly Top")
		(33 "B.Fab" user "Ref Des/Assembly Bottom")
	)
	(footprint ""
		(layer "B.Cu")
		(at 407.949908 -303.499774 -90)
		(property "Reference" "C3428"
			(at 0 0 90)
			(layer "B.SilkS")
			(hide yes)
			(effects
				(font
					(size 1.27 1.27)
				)
				(justify mirror)
			)
		)
		(property "Value" ""
			(at 0 0 90)
			(layer "B.Fab")
			(effects
				(font
					(size 1.27 1.27)
				)
				(justify mirror)
			)
		)
		(duplicate_pad_numbers_are_jumpers no)
		(fp_line
			(start -0.299974 0.150114)
			(end 0.299974 0.150114)
			(stroke
				(width 0.1)
				(type default)
			)
			(layer "B.Fab")
		)
		(fp_line
			(start 0.299974 0.150114)
			(end 0.299974 -0.150114)
			(stroke
				(width 0.1)
				(type default)
			)
			(layer "B.Fab")
		)
		(fp_line
			(start -0.299974 -0.150114)
			(end -0.299974 0.150114)
			(stroke
				(width 0.1)
				(type default)
			)
			(layer "B.Fab")
		)
		(fp_line
			(start 0.299974 -0.150114)
			(end -0.299974 -0.150114)
			(stroke
				(width 0.1)
				(type default)
			)
			(layer "B.Fab")
		)
		(pad "1" smd rect
			(at 0.2667 0 90)
			(size 0.3048 0.381)
			(layers "B.Cu" "B.Mask" "B.Paste")
			(net "P1V25_PEX3")
		)
		(pad "2" smd rect
			(at -0.2667 0 90)
			(size 0.3048 0.381)
			(layers "B.Cu" "B.Mask" "B.Paste")
			(net "GND")
		)
	)
	(footprint ""
		(layer "B.Cu")
		(at 226.047046 -141.443202 -90)
		(property "Reference" "R4198"
			(at 0 0 90)
			(layer "B.SilkS")
			(hide yes)
			(effects
				(font
					(size 1.27 1.27)
				)
				(justify mirror)
			)
		)
		(property "Value" ""
			(at 0 0 90)
			(layer "B.Fab")
			(effects
				(font
					(size 1.27 1.27)
				)
				(justify mirror)
			)
		)
		(duplicate_pad_numbers_are_jumpers no)
		(fp_line
			(start -1.2954 0.5842)
			(end 1.2954 0.5842)
			(stroke
				(width 0.1524)
				(type default)
			)
			(layer "B.SilkS")
		)
		(fp_line
			(start 1.2954 0.5842)
			(end 1.2954 -0.5842)
			(stroke
				(width 0.1524)
				(type default)
			)
			(layer "B.SilkS")
		)
		(fp_line
			(start -1.2954 -0.5842)
			(end -1.2954 0.5842)
			(stroke
				(width 0.1524)
				(type default)
			)
			(layer "B.SilkS")
		)
		(fp_line
			(start 1.2954 -0.5842)
			(end -1.2954 -0.5842)
			(stroke
				(width 0.1524)
				(type default)
			)
			(layer "B.SilkS")
		)
		(fp_line
			(start -0.8636 0.4572)
			(end 0.8636 0.4572)
			(stroke
				(width 0.1)
				(type default)
			)
			(layer "B.Fab")
		)
		(fp_line
			(start 0.8636 0.4572)
			(end 0.8636 0.4318)
			(stroke
				(width 0.1)
				(type default)
			)
			(layer "B.Fab")
		)
		(fp_line
			(start 0.8636 0.4318)
			(end 0.8636 0.4064)
			(stroke
				(width 0.1)
				(type default)
			)
			(layer "B.Fab")
		)
		(fp_line
			(start -1.1938 0.4064)
			(end -0.8636 0.4064)
			(stroke
				(width 0.1)
				(type default)
			)
			(layer "B.Fab")
		)
		(fp_line
			(start -0.8636 0.4064)
			(end -0.8636 0.4572)
			(stroke
				(width 0.1)
				(type default)
			)
			(layer "B.Fab")
		)
		(fp_line
			(start 0.8636 0.4064)
			(end 1.1938 0.4064)
			(stroke
				(width 0.1)
				(type default)
			)
			(layer "B.Fab")
		)
		(fp_line
			(start 1.1938 0.4064)
			(end 1.1938 -0.406654)
			(stroke
				(width 0.1)
				(type default)
			)
			(layer "B.Fab")
		)
		(fp_line
			(start -1.1938 -0.406654)
			(end -1.1938 0.4064)
			(stroke
				(width 0.1)
				(type default)
			)
			(layer "B.Fab")
		)
		(fp_line
			(start -0.8636 -0.406654)
			(end -1.1938 -0.406654)
			(stroke
				(width 0.1)
				(type default)
			)
			(layer "B.Fab")
		)
		(fp_line
			(start 0.8636 -0.406654)
			(end 0.8636 -0.4572)
			(stroke
				(width 0.1)
				(type default)
			)
			(layer "B.Fab")
		)
		(fp_line
			(start 1.1938 -0.406654)
			(end 0.8636 -0.406654)
			(stroke
				(width 0.1)
				(type default)
			)
			(layer "B.Fab")
		)
		(fp_line
			(start -0.8636 -0.4572)
			(end -0.8636 -0.406654)
			(stroke
				(width 0.1)
				(type default)
			)
			(layer "B.Fab")
		)
		(fp_line
			(start 0.8636 -0.4572)
			(end -0.8636 -0.4572)
			(stroke
				(width 0.1)
				(type default)
			)
			(layer "B.Fab")
		)
		(pad "1" smd rect
			(at 0.7366 0 180)
			(size 0.7112 0.8128)
			(layers "B.Cu" "B.Mask" "B.Paste")
			(net "P3V3_CLK_GEN_VDDMXCK_CK440_PEX")
		)
		(pad "2" smd rect
			(at -0.7366 0 180)
			(size 0.7112 0.8128)
			(layers "B.Cu" "B.Mask" "B.Paste")
			(net "P3V3_CLK_GEN_VDDPT_CK440_PEX")
		)
	)
	(footprint ""
		(layer "B.Cu")
		(at 50.624994 -293.99992 90)
		(property "Reference" "C1119"
			(at 0 0 90)
			(layer "B.SilkS")
			(hide yes)
			(effects
				(font
					(size 1.27 1.27)
				)
				(justify mirror)
			)
		)
		(property "Value" ""
			(at 0 0 90)
			(layer "B.Fab")
			(effects
				(font
					(size 1.27 1.27)
				)
				(justify mirror)
			)
		)
		(duplicate_pad_numbers_are_jumpers no)
		(fp_line
			(start 0.299974 -0.150114)
			(end -0.299974 -0.150114)
			(stroke
				(width 0.1)
				(type default)
			)
			(layer "B.Fab")
		)
		(fp_line
			(start -0.299974 -0.150114)
			(end -0.299974 0.150114)
			(stroke
				(width 0.1)
				(type default)
			)
			(layer "B.Fab")
		)
		(fp_line
			(start 0.299974 0.150114)
			(end 0.299974 -0.150114)
			(stroke
				(width 0.1)
				(type default)
			)
			(layer "B.Fab")
		)
		(fp_line
			(start -0.299974 0.150114)
			(end 0.299974 0.150114)
			(stroke
				(width 0.1)
				(type default)
			)
			(layer "B.Fab")
		)
		(pad "1" smd rect
			(at 0.2667 0 270)
			(size 0.3048 0.381)
			(layers "B.Cu" "B.Mask" "B.Paste")
			(net "P0V8_PEX0")
		)
		(pad "2" smd rect
			(at -0.2667 0 270)
			(size 0.3048 0.381)
			(layers "B.Cu" "B.Mask" "B.Paste")
			(net "GND")
		)
	)
	(footprint ""
		(layer "B.Cu")
		(at 126.328678 -285.606998 -90)
		(property "Reference" "PR7177"
			(at 0 0 90)
			(layer "B.SilkS")
			(hide yes)
			(effects
				(font
					(size 1.27 1.27)
				)
				(justify mirror)
			)
		)
		(property "Value" ""
			(at 0 0 90)
			(layer "B.Fab")
			(effects
				(font
					(size 1.27 1.27)
				)
				(justify mirror)
			)
		)
		(duplicate_pad_numbers_are_jumpers no)
		(fp_line
			(start -0.7874 0.4064)
			(end 0.7874 0.4064)
			(stroke
				(width 0.1524)
				(type default)
			)
			(layer "B.SilkS")
		)
		(fp_line
			(start 0.7874 0.4064)
			(end 0.7874 -0.4064)
			(stroke
				(width 0.1524)
				(type default)
			)
			(layer "B.SilkS")
		)
		(fp_line
			(start -0.7874 -0.4064)
			(end -0.7874 0.4064)
			(stroke
				(width 0.1524)
				(type default)
			)
			(layer "B.SilkS")
		)
		(fp_line
			(start 0.7874 -0.4064)
			(end -0.7874 -0.4064)
			(stroke
				(width 0.1524)
				(type default)
			)
			(layer "B.SilkS")
		)
		(fp_line
			(start -0.67945 0.3048)
			(end -0.120396 0.3048)
			(stroke
				(width 0.1)
				(type default)
			)
			(layer "B.Fab")
		)
		(fp_line
			(start -0.120396 0.3048)
			(end -0.120396 0.2794)
			(stroke
				(width 0.1)
				(type default)
			)
			(layer "B.Fab")
		)
		(fp_line
			(start 0.12065 0.3048)
			(end 0.67945 0.3048)
			(stroke
				(width 0.1)
				(type default)
			)
			(layer "B.Fab")
		)
		(fp_line
			(start 0.67945 0.3048)
			(end 0.67945 -0.305054)
			(stroke
				(width 0.1)
				(type default)
			)
			(layer "B.Fab")
		)
		(fp_line
			(start -0.120396 0.2794)
			(end 0.12065 0.2794)
			(stroke
				(width 0.1)
				(type default)
			)
			(layer "B.Fab")
		)
		(fp_line
			(start 0.12065 0.2794)
			(end 0.12065 0.3048)
			(stroke
				(width 0.1)
				(type default)
			)
			(layer "B.Fab")
		)
		(fp_line
			(start -0.12065 -0.2794)
			(end -0.12065 -0.3048)
			(stroke
				(width 0.1)
				(type default)
			)
			(layer "B.Fab")
		)
		(fp_line
			(start 0.12065 -0.2794)
			(end -0.12065 -0.2794)
			(stroke
				(width 0.1)
				(type default)
			)
			(layer "B.Fab")
		)
		(fp_line
			(start -0.67945 -0.3048)
			(end -0.67945 0.3048)
			(stroke
				(width 0.1)
				(type default)
			)
			(layer "B.Fab")
		)
		(fp_line
			(start -0.12065 -0.3048)
			(end -0.67945 -0.3048)
			(stroke
				(width 0.1)
				(type default)
			)
			(layer "B.Fab")
		)
		(fp_line
			(start 0.12065 -0.305054)
			(end 0.12065 -0.2794)
			(stroke
				(width 0.1)
				(type default)
			)
			(layer "B.Fab")
		)
		(fp_line
			(start 0.67945 -0.305054)
			(end 0.12065 -0.305054)
			(stroke
				(width 0.1)
				(type default)
			)
			(layer "B.Fab")
		)
		(pad "1" smd circle
			(at 0.40005 0 90)
			(size 0 0)
			(layers "B.Cu" "B.Mask" "B.Paste")
			(net "P0V8_PEX1_PVCC")
		)
		(pad "2" smd circle
			(at -0.40005 0 90)
			(size 0 0)
			(layers "B.Cu" "B.Mask" "B.Paste")
			(net "P3V3_AUX")
		)
	)
	(footprint ""
		(layer "B.Cu")
		(at 386.842 -246.253 90)
		(property "Reference" "C2606"
			(at 0 0 90)
			(layer "B.SilkS")
			(hide yes)
			(effects
				(font
					(size 1.27 1.27)
				)
				(justify mirror)
			)
		)
		(property "Value" ""
			(at 0 0 90)
			(layer "B.Fab")
			(effects
				(font
					(size 1.27 1.27)
				)
				(justify mirror)
			)
		)
		(duplicate_pad_numbers_are_jumpers no)
		(fp_line
			(start 0.7874 -0.4064)
			(end -0.7874 -0.4064)
			(stroke
				(width 0.1524)
				(type default)
			)
			(layer "B.SilkS")
		)
		(fp_line
			(start -0.7874 -0.4064)
			(end -0.7874 0.4064)
			(stroke
				(width 0.1524)
				(type default)
			)
			(layer "B.SilkS")
		)
		(fp_line
			(start 0.7874 0.4064)
			(end 0.7874 -0.4064)
			(stroke
				(width 0.1524)
				(type default)
			)
			(layer "B.SilkS")
		)
		(fp_line
			(start -0.7874 0.4064)
			(end 0.7874 0.4064)
			(stroke
				(width 0.1524)
				(type default)
			)
			(layer "B.SilkS")
		)
		(fp_line
			(start 0.67945 -0.305054)
			(end 0.12065 -0.305054)
			(stroke
				(width 0.1)
				(type default)
			)
			(layer "B.Fab")
		)
		(fp_line
			(start 0.12065 -0.305054)
			(end 0.12065 -0.2794)
			(stroke
				(width 0.1)
				(type default)
			)
			(layer "B.Fab")
		)
		(fp_line
			(start -0.12065 -0.3048)
			(end -0.67945 -0.3048)
			(stroke
				(width 0.1)
				(type default)
			)
			(layer "B.Fab")
		)
		(fp_line
			(start -0.67945 -0.3048)
			(end -0.67945 0.3048)
			(stroke
				(width 0.1)
				(type default)
			)
			(layer "B.Fab")
		)
		(fp_line
			(start 0.12065 -0.2794)
			(end -0.12065 -0.2794)
			(stroke
				(width 0.1)
				(type default)
			)
			(layer "B.Fab")
		)
		(fp_line
			(start -0.12065 -0.2794)
			(end -0.12065 -0.3048)
			(stroke
				(width 0.1)
				(type default)
			)
			(layer "B.Fab")
		)
		(fp_line
			(start 0.12065 0.2794)
			(end 0.12065 0.3048)
			(stroke
				(width 0.1)
				(type default)
			)
			(layer "B.Fab")
		)
		(fp_line
			(start -0.120396 0.2794)
			(end 0.12065 0.2794)
			(stroke
				(width 0.1)
				(type default)
			)
			(layer "B.Fab")
		)
		(fp_line
			(start 0.67945 0.3048)
			(end 0.67945 -0.305054)
			(stroke
				(width 0.1)
				(type default)
			)
			(layer "B.Fab")
		)
		(fp_line
			(start 0.12065 0.3048)
			(end 0.67945 0.3048)
			(stroke
				(width 0.1)
				(type default)
			)
			(layer "B.Fab")
		)
		(fp_line
			(start -0.120396 0.3048)
			(end -0.120396 0.2794)
			(stroke
				(width 0.1)
				(type default)
			)
			(layer "B.Fab")
		)
		(fp_line
			(start -0.67945 0.3048)
			(end -0.120396 0.3048)
			(stroke
				(width 0.1)
				(type default)
			)
			(layer "B.Fab")
		)
		(pad "1" smd circle
			(at 0.40005 0 270)
			(size 0 0)
			(layers "B.Cu" "B.Mask" "B.Paste")
			(net "GND")
		)
		(pad "2" smd circle
			(at -0.40005 0 270)
			(size 0 0)
			(layers "B.Cu" "B.Mask" "B.Paste")
			(net "P3V3_AUX")
		)
	)
	(footprint ""
		(layer "B.Cu")
		(at 350.491044 -224.795334 180)
		(property "Reference" "C2041"
			(at 0 0 0)
			(layer "B.SilkS")
			(hide yes)
			(effects
				(font
					(size 1.27 1.27)
				)
				(justify mirror)
			)
		)
		(property "Value" ""
			(at 0 0 0)
			(layer "B.Fab")
			(effects
				(font
					(size 1.27 1.27)
				)
				(justify mirror)
			)
		)
		(duplicate_pad_numbers_are_jumpers no)
		(fp_line
			(start 0.69215 0.2921)
			(end 0.69215 -0.2921)
			(stroke
				(width 0.1524)
				(type default)
			)
			(layer "B.SilkS")
		)
		(fp_line
			(start 0.69215 -0.2921)
			(end -0.69215 -0.2921)
			(stroke
				(width 0.1524)
				(type default)
			)
			(layer "B.SilkS")
		)
		(fp_line
			(start -0.69215 0.2921)
			(end 0.69215 0.2921)
			(stroke
				(width 0.1524)
				(type default)
			)
			(layer "B.SilkS")
		)
		(fp_line
			(start -0.69215 -0.2921)
			(end -0.69215 0.2921)
			(stroke
				(width 0.1524)
				(type default)
			)
			(layer "B.SilkS")
		)
		(fp_line
			(start 0.51435 0.2794)
			(end 0.51435 -0.2794)
			(stroke
				(width 0.1)
				(type default)
			)
			(layer "B.Fab")
		)
		(fp_line
			(start 0.51435 -0.2794)
			(end -0.51435 -0.2794)
			(stroke
				(width 0.1)
				(type default)
			)
			(layer "B.Fab")
		)
		(fp_line
			(start -0.51435 0.2794)
			(end 0.51435 0.2794)
			(stroke
				(width 0.1)
				(type default)
			)
			(layer "B.Fab")
		)
		(fp_line
			(start -0.51435 -0.2794)
			(end -0.51435 0.2794)
			(stroke
				(width 0.1)
				(type default)
			)
			(layer "B.Fab")
		)
		(pad "1" smd circle
			(at 0.40005 0)
			(size 0 0)
			(layers "B.Cu" "B.Mask" "B.Paste")
			(net "P3V3_FPGA_VCCIO1")
		)
		(pad "2" smd circle
			(at -0.40005 0)
			(size 0 0)
			(layers "B.Cu" "B.Mask" "B.Paste")
			(net "GND")
		)
		(zone
			(layer "B.Cu")
			(hatch none 0.5)
			(connect_pads
				(clearance 0)
			)
			(min_thickness 0.25)
			(keepout
				(tracks not_allowed)
				(vias allowed)
				(pads allowed)
				(copperpour not_allowed)
				(footprints allowed)
			)
			(placement
				(enabled no)
				(sheetname "")
			)
			(fill
				(thermal_gap 0.5)
				(thermal_bridge_width 0.5)
				(island_removal_mode 0)
			)
			(polygon
				(pts
					(xy 350.300544 -224.882964) (xy 350.391984 -224.94113) (xy 350.591374 -224.94113) (xy 350.681544 -224.882964)
					(xy 350.681544 -224.707704) (xy 350.591374 -224.649284) (xy 350.391984 -224.649284) (xy 350.300544 -224.70745)
				)
			)
		)
	)
	(footprint ""
		(layer "B.Cu")
		(at 167.200072 -292.099746 90)
		(property "Reference" "C1442"
			(at 0 0 90)
			(layer "B.SilkS")
			(hide yes)
			(effects
				(font
					(size 1.27 1.27)
				)
				(justify mirror)
			)
		)
		(property "Value" ""
			(at 0 0 90)
			(layer "B.Fab")
			(effects
				(font
					(size 1.27 1.27)
				)
				(justify mirror)
			)
		)
		(duplicate_pad_numbers_are_jumpers no)
		(fp_line
			(start 0.299974 -0.150114)
			(end -0.299974 -0.150114)
			(stroke
				(width 0.1)
				(type default)
			)
			(layer "B.Fab")
		)
		(fp_line
			(start -0.299974 -0.150114)
			(end -0.299974 0.150114)
			(stroke
				(width 0.1)
				(type default)
			)
			(layer "B.Fab")
		)
		(fp_line
			(start 0.299974 0.150114)
			(end 0.299974 -0.150114)
			(stroke
				(width 0.1)
				(type default)
			)
			(layer "B.Fab")
		)
		(fp_line
			(start -0.299974 0.150114)
			(end 0.299974 0.150114)
			(stroke
				(width 0.1)
				(type default)
			)
			(layer "B.Fab")
		)
		(pad "1" smd rect
			(at 0.2667 0 270)
			(size 0.3048 0.381)
			(layers "B.Cu" "B.Mask" "B.Paste")
			(net "P0V8_SERDES_VDDA_PEX1")
		)
		(pad "2" smd rect
			(at -0.2667 0 270)
			(size 0.3048 0.381)
			(layers "B.Cu" "B.Mask" "B.Paste")
			(net "GND")
		)
	)
	(footprint ""
		(layer "B.Cu")
		(at 170.964606 -140.931138 180)
		(property "Reference" "U18"
			(at -0.478282 1.872234 0)
			(unlocked yes)
			(layer "B.SilkS")
			(effects
				(font
					(size 0.7874 0.5842)
					(thickness 0.1524)
				)
				(justify mirror)
			)
		)
		(property "Value" ""
			(at 0 0 0)
			(layer "B.Fab")
			(effects
				(font
					(size 1.27 1.27)
				)
				(justify mirror)
			)
		)
		(duplicate_pad_numbers_are_jumpers no)
		(fp_line
			(start 1.3462 1.1938)
			(end -1.3462 1.1938)
			(stroke
				(width 0.1524)
				(type default)
			)
			(layer "B.SilkS")
		)
		(fp_line
			(start 1.3462 -1.1938)
			(end 1.3462 1.1684)
			(stroke
				(width 0.1524)
				(type default)
			)
			(layer "B.SilkS")
		)
		(fp_line
			(start -1.3462 1.1938)
			(end -1.3462 -1.1938)
			(stroke
				(width 0.1524)
				(type default)
			)
			(layer "B.SilkS")
		)
		(fp_line
			(start -1.3462 -1.1938)
			(end 1.3462 -1.1938)
			(stroke
				(width 0.1524)
				(type default)
			)
			(layer "B.SilkS")
		)
		(fp_poly
			(pts
				(xy 1.447038 -0.760476) (xy 2.052066 -0.457962) (xy 2.052066 -1.06299)
			)
			(stroke
				(width 0)
				(type default)
			)
			(fill yes)
			(layer "B.SilkS")
		)
		(fp_line
			(start 0.674878 1.124966)
			(end -0.674878 1.124966)
			(stroke
				(width 0.1)
				(type default)
			)
			(layer "B.Fab")
		)
		(fp_line
			(start 0.674878 -1.124966)
			(end 0.674878 1.124966)
			(stroke
				(width 0.1)
				(type default)
			)
			(layer "B.Fab")
		)
		(fp_line
			(start -0.674878 1.124966)
			(end -0.674878 -1.124966)
			(stroke
				(width 0.1)
				(type default)
			)
			(layer "B.Fab")
		)
		(fp_line
			(start -0.674878 -1.124966)
			(end 0.674878 -1.124966)
			(stroke
				(width 0.1)
				(type default)
			)
			(layer "B.Fab")
		)
		(fp_poly
			(pts
				(xy 1.447038 -0.760476) (xy 2.052066 -0.457962) (xy 2.052066 -1.06299)
			)
			(stroke
				(width 0)
				(type default)
			)
			(fill yes)
			(layer "B.Fab")
		)
		(pad "1" smd rect
			(at 0.899922 -0.750062)
			(size 0.6096 0.6096)
			(layers "B.Cu" "B.Mask" "B.Paste")
			(net "NIC2_AUX_PWR_EN_R")
		)
		(pad "2" smd rect
			(at 0.899922 0 270)
			(size 0.4064 0.6096)
			(layers "B.Cu" "B.Mask" "B.Paste")
			(net "RST_SMB_NIC2_MUX_N")
		)
		(pad "3" smd rect
			(at 0.899922 0.750062)
			(size 0.6096 0.6096)
			(layers "B.Cu" "B.Mask" "B.Paste")
			(net "GND")
		)
		(pad "4" smd rect
			(at -0.899922 0.750062)
			(size 0.6096 0.6096)
			(layers "B.Cu" "B.Mask" "B.Paste")
			(net "RST_SMB_NIC2_MUX_ISO_N")
		)
		(pad "5" smd rect
			(at -0.899922 -0.750062)
			(size 0.6096 0.6096)
			(layers "B.Cu" "B.Mask" "B.Paste")
			(net "P3V3_AUX")
		)
	)
)
